# T6G (Grand Teton) — schematic netlist excerpt (pin names and nets, part order shuffled) for the footprints in the layout excerpt that follows; sources: Cadence DE-HDL packaged netlist, KiCad conversion of 04192023_DAF0TMB3IC0_F0TG_MB_C_brd_V02_OCP.brd

R692  Q_RES  49.9 1% CHIP  pkg 0201LF  page 342 : A = SMB_RT_CPU1_P2_ROM_MUX_1D_SDA ; B = SMB_RT_CPU1_P2_ROM_MUX_1D_R_SDA
PR79  Q_RES  2.2 1% CHIP  pkg 0402LF  page 201 : A = PVDDCR_CPU1_P0_PVCC ; B = PVDDCR_CPU1_P0_VCC1

Q137  MOSFET_NCH_DUAL  PJT138K IC  pkg SOT363XD  page 124
  S1  = GND
  G1  = GPU_3V3IO_RSVD3
  D2  = GPU_3V3IO_RSVD3_ISO
  S2  = GND
  G2  = GPU_3V3IO_RSVD3_N
  D1  = GPU_3V3IO_RSVD3_N

(kicad_pcb
	(version 20260206)
	(generator "pcbnew")
	(generator_version "10.0")
	(general
		(thickness 1.6)
		(legacy_teardrops no)
	)
	(paper "A4")
	(title_block
		(title "04192023_DAF0TMB3IC0_F0TG_MB_C_brd_V02_OCP.brd")
		(comment 1 "Grand Teton / footprints 5494-5496 of 8354")
	)
	(layers
		(0 "F.Cu" signal "TOP")
		(4 "In1.Cu" signal "GND")
		(6 "In2.Cu" signal "IN1")
		(8 "In3.Cu" signal "GND1")
		(10 "In4.Cu" signal "IN2")
		(12 "In5.Cu" signal "GND2")
		(14 "In6.Cu" signal "IN3")
		(16 "In7.Cu" signal "GND3")
		(18 "In8.Cu" signal "VCC")
		(20 "In9.Cu" signal "VCC1")
		(22 "In10.Cu" signal "GND4")
		(24 "In11.Cu" signal "IN4")
		(26 "In12.Cu" signal "GND5")
		(28 "In13.Cu" signal "IN5")
		(30 "In14.Cu" signal "GND6")
		(32 "In15.Cu" signal "IN6")
		(34 "In16.Cu" signal "GND7")
		(2 "B.Cu" signal "BOTTOM")
		(9 "F.Adhes" user "F.Adhesive")
		(11 "B.Adhes" user "B.Adhesive")
		(13 "F.Paste" user "Package Geometry/Pastemask Top")
		(15 "B.Paste" user "Package Geometry/Pastemask Bottom")
		(5 "F.SilkS" user "Ref Des/Silkscreen Top")
		(7 "B.SilkS" user "Ref Des/Silkscreen Bottom")
		(1 "F.Mask" user "Board Geometry/Soldermask Top")
		(3 "B.Mask" user "Board Geometry/Soldermask Bottom")
		(17 "Dwgs.User" user "User.Drawings")
		(19 "Cmts.User" user "User.Comments")
		(21 "Eco1.User" user "User.Eco1")
		(23 "Eco2.User" user "User.Eco2")
		(25 "Edge.Cuts" user "Board Geometry/Outline")
		(27 "Margin" user)
		(31 "F.CrtYd" user "Package Geometry/Place Bound Top")
		(29 "B.CrtYd" user "Package Geometry/Place Bound Bottom")
		(35 "F.Fab" user "Ref Des/Assembly Top")
		(33 "B.Fab" user "Ref Des/Assembly Bottom")
	)
	(footprint ""
		(layer "B.Cu")
		(at 163.4236 -412.18866 90)
		(property "Reference" "R692"
			(at 0 0 90)
			(layer "B.SilkS")
			(hide yes)
			(effects
				(font
					(size 1.27 1.27)
				)
				(justify mirror)
			)
		)
		(property "Value" ""
			(at 0 0 90)
			(layer "B.Fab")
			(effects
				(font
					(size 1.27 1.27)
				)
				(justify mirror)
			)
		)
		(duplicate_pad_numbers_are_jumpers no)
		(fp_line
			(start 0.32512 -0.175006)
			(end -0.32512 -0.175006)
			(stroke
				(width 0.1)
				(type default)
			)
			(layer "B.Fab")
		)
		(fp_line
			(start -0.32512 -0.175006)
			(end -0.32512 0.175006)
			(stroke
				(width 0.1)
				(type default)
			)
			(layer "B.Fab")
		)
		(fp_line
			(start 0.32512 0.175006)
			(end 0.32512 -0.175006)
			(stroke
				(width 0.1)
				(type default)
			)
			(layer "B.Fab")
		)
		(fp_line
			(start -0.32512 0.175006)
			(end 0.32512 0.175006)
			(stroke
				(width 0.1)
				(type default)
			)
			(layer "B.Fab")
		)
		(pad "1" smd rect
			(at 0.2667 0 270)
			(size 0.3048 0.381)
			(layers "B.Cu" "B.Mask" "B.Paste")
			(net "SMB_RT_CPU1_P2_ROM_MUX_1D_SDA")
		)
		(pad "2" smd rect
			(at -0.2667 0 90)
			(size 0.3048 0.381)
			(layers "B.Cu" "B.Mask" "B.Paste")
			(net "SMB_RT_CPU1_P2_ROM_MUX_1D_R_SDA")
		)
	)
	(footprint ""
		(layer "B.Cu")
		(at 332.748128 -336.032856 -90)
		(property "Reference" "PR79"
			(at 0 0 90)
			(layer "B.SilkS")
			(hide yes)
			(effects
				(font
					(size 1.27 1.27)
				)
				(justify mirror)
			)
		)
		(property "Value" ""
			(at 0 0 90)
			(layer "B.Fab")
			(effects
				(font
					(size 1.27 1.27)
				)
				(justify mirror)
			)
		)
		(duplicate_pad_numbers_are_jumpers no)
		(fp_line
			(start -0.7874 0.4064)
			(end 0.7874 0.4064)
			(stroke
				(width 0.1524)
				(type default)
			)
			(layer "B.SilkS")
		)
		(fp_line
			(start 0.7874 0.4064)
			(end 0.7874 -0.4064)
			(stroke
				(width 0.1524)
				(type default)
			)
			(layer "B.SilkS")
		)
		(fp_line
			(start -0.7874 -0.4064)
			(end -0.7874 0.4064)
			(stroke
				(width 0.1524)
				(type default)
			)
			(layer "B.SilkS")
		)
		(fp_line
			(start 0.7874 -0.4064)
			(end -0.7874 -0.4064)
			(stroke
				(width 0.1524)
				(type default)
			)
			(layer "B.SilkS")
		)
		(fp_line
			(start -0.67945 0.3048)
			(end -0.120396 0.3048)
			(stroke
				(width 0.1)
				(type default)
			)
			(layer "B.Fab")
		)
		(fp_line
			(start -0.120396 0.3048)
			(end -0.120396 0.2794)
			(stroke
				(width 0.1)
				(type default)
			)
			(layer "B.Fab")
		)
		(fp_line
			(start 0.12065 0.3048)
			(end 0.67945 0.3048)
			(stroke
				(width 0.1)
				(type default)
			)
			(layer "B.Fab")
		)
		(fp_line
			(start 0.67945 0.3048)
			(end 0.67945 -0.305054)
			(stroke
				(width 0.1)
				(type default)
			)
			(layer "B.Fab")
		)
		(fp_line
			(start -0.120396 0.2794)
			(end 0.12065 0.2794)
			(stroke
				(width 0.1)
				(type default)
			)
			(layer "B.Fab")
		)
		(fp_line
			(start 0.12065 0.2794)
			(end 0.12065 0.3048)
			(stroke
				(width 0.1)
				(type default)
			)
			(layer "B.Fab")
		)
		(fp_line
			(start -0.12065 -0.2794)
			(end -0.12065 -0.3048)
			(stroke
				(width 0.1)
				(type default)
			)
			(layer "B.Fab")
		)
		(fp_line
			(start 0.12065 -0.2794)
			(end -0.12065 -0.2794)
			(stroke
				(width 0.1)
				(type default)
			)
			(layer "B.Fab")
		)
		(fp_line
			(start -0.67945 -0.3048)
			(end -0.67945 0.3048)
			(stroke
				(width 0.1)
				(type default)
			)
			(layer "B.Fab")
		)
		(fp_line
			(start -0.12065 -0.3048)
			(end -0.67945 -0.3048)
			(stroke
				(width 0.1)
				(type default)
			)
			(layer "B.Fab")
		)
		(fp_line
			(start 0.12065 -0.305054)
			(end 0.12065 -0.2794)
			(stroke
				(width 0.1)
				(type default)
			)
			(layer "B.Fab")
		)
		(fp_line
			(start 0.67945 -0.305054)
			(end 0.12065 -0.305054)
			(stroke
				(width 0.1)
				(type default)
			)
			(layer "B.Fab")
		)
		(pad "1" smd circle
			(at 0.40005 0 90)
			(size 0 0)
			(layers "B.Cu" "B.Mask" "B.Paste")
			(net "PVDDCR_CPU1_P0_PVCC")
		)
		(pad "2" smd circle
			(at -0.40005 0 90)
			(size 0 0)
			(layers "B.Cu" "B.Mask" "B.Paste")
			(net "PVDDCR_CPU1_P0_VCC1")
		)
	)
	(footprint ""
		(layer "B.Cu")
		(at 432.21402 -437.142636 180)
		(property "Reference" "Q137"
			(at -1.600708 -3.202686 0)
			(unlocked yes)
			(layer "B.SilkS")
			(effects
				(font
					(size 0.7874 0.5842)
					(thickness 0.1524)
				)
				(justify left mirror)
			)
		)
		(property "Value" ""
			(at 0 0 0)
			(layer "B.Fab")
			(effects
				(font
					(size 1.27 1.27)
				)
				(justify mirror)
			)
		)
		(duplicate_pad_numbers_are_jumpers no)
		(fp_line
			(start 1.332738 1.100074)
			(end 1.332738 -1.100074)
			(stroke
				(width 0.1524)
				(type default)
			)
			(layer "B.SilkS")
		)
		(fp_line
			(start 1.332738 -1.100074)
			(end 0.4826 -1.100074)
			(stroke
				(width 0.1524)
				(type default)
			)
			(layer "B.SilkS")
		)
		(fp_line
			(start 0.4826 -1.100074)
			(end 0 -0.541274)
			(stroke
				(width 0.1524)
				(type default)
			)
			(layer "B.SilkS")
		)
		(fp_line
			(start 0 -0.541274)
			(end -0.4826 -1.100074)
			(stroke
				(width 0.1524)
				(type default)
			)
			(layer "B.SilkS")
		)
		(fp_line
			(start -0.4826 -1.100074)
			(end -1.332738 -1.100074)
			(stroke
				(width 0.1524)
				(type default)
			)
			(layer "B.SilkS")
		)
		(fp_line
			(start -1.332738 1.100074)
			(end 1.332738 1.100074)
			(stroke
				(width 0.1524)
				(type default)
			)
			(layer "B.SilkS")
		)
		(fp_line
			(start -1.332738 -1.100074)
			(end -1.332738 1.100074)
			(stroke
				(width 0.1524)
				(type default)
			)
			(layer "B.SilkS")
		)
		(fp_poly
			(pts
				(xy 1.255522 -1.262126) (xy 2.00025 -1.510284) (xy 1.50368 -2.006854)
			)
			(stroke
				(width 0)
				(type default)
			)
			(fill yes)
			(layer "B.SilkS")
		)
		(fp_line
			(start 0.674878 1.100074)
			(end 0.674878 -1.100074)
			(stroke
				(width 0.1)
				(type default)
			)
			(layer "B.Fab")
		)
		(fp_line
			(start 0.674878 -1.100074)
			(end -0.674878 -1.100074)
			(stroke
				(width 0.1)
				(type default)
			)
			(layer "B.Fab")
		)
		(fp_line
			(start -0.674878 1.100074)
			(end 0.674878 1.100074)
			(stroke
				(width 0.1)
				(type default)
			)
			(layer "B.Fab")
		)
		(fp_line
			(start -0.674878 -1.100074)
			(end -0.674878 1.100074)
			(stroke
				(width 0.1)
				(type default)
			)
			(layer "B.Fab")
		)
		(fp_poly
			(pts
				(xy 2.2352 -0.298958) (xy 2.2352 -1.001014) (xy 1.533144 -0.649986)
			)
			(stroke
				(width 0)
				(type default)
			)
			(fill yes)
			(layer "B.Fab")
		)
		(pad "1" smd rect
			(at 0.94996 -0.649986 270)
			(size 0.4318 0.508)
			(layers "B.Cu" "B.Mask" "B.Paste")
			(net "GND")
		)
		(pad "2" smd rect
			(at 0.94996 0 270)
			(size 0.4318 0.508)
			(layers "B.Cu" "B.Mask" "B.Paste")
			(net "GPU_3V3IO_RSVD3")
		)
		(pad "3" smd rect
			(at 0.94996 0.649986 270)
			(size 0.4318 0.508)
			(layers "B.Cu" "B.Mask" "B.Paste")
			(net "GPU_3V3IO_RSVD3_ISO")
		)
		(pad "4" smd rect
			(at -0.94996 0.649986 270)
			(size 0.4318 0.508)
			(layers "B.Cu" "B.Mask" "B.Paste")
			(net "GND")
		)
		(pad "5" smd rect
			(at -0.94996 0 270)
			(size 0.4318 0.508)
			(layers "B.Cu" "B.Mask" "B.Paste")
			(net "GPU_3V3IO_RSVD3_N")
		)
		(pad "6" smd rect
			(at -0.94996 -0.649986 270)
			(size 0.4318 0.508)
			(layers "B.Cu" "B.Mask" "B.Paste")
			(net "GPU_3V3IO_RSVD3_N")
		)
	)
)
